(kicad_pcb
	(version 20241229)
	(generator "pcbnew")
	(generator_version "9.0")
	(general
		(thickness 1.711)
		(legacy_teardrops no)
	)
	(paper "A4")
	(title_block
		(title "Antmicro Baseboard for Jetson AGX Thor")
		(date "2026-02-18")
		(rev "1.1.0")
		(company "Antmicro Ltd")
		(comment 1 "www.antmicro.com")
		(comment 9 "footprints 365-369 of 1170")
	)
	(layers
		(0 "F.Cu" signal)
		(4 "In1.Cu" signal)
		(6 "In2.Cu" signal)
		(8 "In3.Cu" signal)
		(10 "In4.Cu" jumper)
		(12 "In5.Cu" signal)
		(14 "In6.Cu" signal)
		(16 "In7.Cu" signal)
		(18 "In8.Cu" signal)
		(2 "B.Cu" signal)
		(9 "F.Adhes" user "F.Adhesive")
		(11 "B.Adhes" user "B.Adhesive")
		(13 "F.Paste" user)
		(15 "B.Paste" user)
		(5 "F.SilkS" user "F.Silkscreen")
		(7 "B.SilkS" user "B.Silkscreen")
		(1 "F.Mask" user)
		(3 "B.Mask" user)
		(17 "Dwgs.User" user "User.Drawings")
		(19 "Cmts.User" user "User.Comments")
		(21 "Eco1.User" user "User.Eco1")
		(23 "Eco2.User" user "User.Eco2")
		(25 "Edge.Cuts" user)
		(27 "Margin" user)
		(31 "F.CrtYd" user "F.Courtyard")
		(29 "B.CrtYd" user "B.Courtyard")
		(35 "F.Fab" user)
		(33 "B.Fab" user)
	)
	(footprint "antmicro-footprints:R_0402_1005Metric"
		(layer "F.Cu")
		(at 183.809468 68.67 90)
		(descr "Resistor SMD 0402")
		(tags "resistor SMD 0402")
		(property "Reference" "R125"
			(at -1.4 2.61 90)
			(layer "F.SilkS")
			(effects
				(font
					(size 0.7 0.7)
					(thickness 0.15)
				)
				(justify left bottom)
			)
		)
		(property "Value" "R_10k_0402"
			(at -1.011843 1.772047 90)
			(layer "F.Fab")
			(effects
				(font
					(size 0.7 0.7)
					(thickness 0.15)
				)
				(justify left bottom)
			)
		)
		(property "Datasheet" "https://www.bourns.com/docs/product-datasheets/cr.pdf"
			(at 0 0 90)
			(layer "F.Fab")
			(hide yes)
			(effects
				(font
					(size 1.27 1.27)
					(thickness 0.15)
				)
			)
		)
		(property "Description" "SMD Chip Resistor, 10 kohm, ± 1%, 62.5 mW, 0402 [1005 Metric], Thick Film, General Purpose"
			(at 0 0 90)
			(layer "F.Fab")
			(hide yes)
			(effects
				(font
					(size 1.27 1.27)
					(thickness 0.15)
				)
			)
		)
		(property "MPN" "CR0402-FX-1002GLF"
			(at 0 0 90)
			(unlocked yes)
			(layer "F.Fab")
			(hide yes)
			(effects
				(font
					(size 1 1)
					(thickness 0.15)
				)
			)
		)
		(property "Manufacturer" "Bourns"
			(at 0 0 90)
			(unlocked yes)
			(layer "F.Fab")
			(hide yes)
			(effects
				(font
					(size 1 1)
					(thickness 0.15)
				)
			)
		)
		(property "License" "Apache-2.0"
			(at 0 0 90)
			(unlocked yes)
			(layer "F.Fab")
			(hide yes)
			(effects
				(font
					(size 1 1)
					(thickness 0.15)
				)
			)
		)
		(property "Author" "Antmicro"
			(at 0 0 90)
			(unlocked yes)
			(layer "F.Fab")
			(hide yes)
			(effects
				(font
					(size 1 1)
					(thickness 0.15)
				)
			)
		)
		(property "Val" "10k"
			(at 0 0 90)
			(unlocked yes)
			(layer "F.Fab")
			(hide yes)
			(effects
				(font
					(size 1 1)
					(thickness 0.15)
				)
			)
		)
		(property "Tolerance" "1%"
			(at 0 0 90)
			(unlocked yes)
			(layer "F.Fab")
			(hide yes)
			(effects
				(font
					(size 1 1)
					(thickness 0.15)
				)
			)
		)
		(component_classes
			(class "DCDC_20V")
		)
		(sheetname "/DCDC/")
		(sheetfile "dcdc.kicad_sch")
		(attr smd)
		(fp_rect
			(start -0.925 -0.47)
			(end 0.925 0.47)
			(stroke
				(width 0.05)
				(type default)
			)
			(fill no)
			(layer "F.CrtYd")
		)
		(fp_rect
			(start -0.5 -0.25)
			(end 0.5 0.25)
			(stroke
				(width 0.15)
				(type solid)
			)
			(fill no)
			(layer "F.Fab")
		)
		(fp_text user "Author: Antmicro"
			(at -0.95 4.169 90)
			(layer "F.Fab")
			(effects
				(font
					(size 0.7 0.7)
					(thickness 0.15)
				)
				(justify left bottom)
			)
		)
		(fp_text user "${REFERENCE}"
			(at -0.95 3.168 90)
			(layer "F.Fab")
			(effects
				(font
					(size 0.7 0.7)
					(thickness 0.15)
				)
				(justify left bottom)
			)
		)
		(fp_text user "License: Apache-2.0"
			(at -0.95 5.169 90)
			(layer "F.Fab")
			(effects
				(font
					(size 0.7 0.7)
					(thickness 0.15)
				)
				(justify left bottom)
			)
		)
		(pad "1" smd roundrect
			(at -0.48 0 90)
			(size 0.59 0.64)
			(layers "F.Cu" "F.Mask" "F.Paste")
			(roundrect_rratio 0.25)
			(net 1 "GND")
			(pintype "passive")
		)
		(pad "2" smd roundrect
			(at 0.48 0 90)
			(size 0.59 0.64)
			(layers "F.Cu" "F.Mask" "F.Paste")
			(roundrect_rratio 0.25)
			(net 1220 "/DCDC/20V_FB")
			(pintype "passive")
		)
	)
	(footprint "antmicro-footprints:C_0805_2012Metric"
		(layer "F.Cu")
		(at 72.6 131 -90)
		(descr "Capacitor SMD 0805")
		(tags "capacitor SMD 0805")
		(property "Reference" "C228"
			(at -3.8 -1.4 90)
			(layer "F.SilkS")
			(effects
				(font
					(size 0.7 0.7)
					(thickness 0.15)
				)
				(justify right top)
			)
		)
		(property "Value" "C_22u_25V_0805"
			(at -2.055717 1.963153 90)
			(layer "F.Fab")
			(effects
				(font
					(size 0.7 0.7)
					(thickness 0.15)
				)
				(justify right top)
			)
		)
		(property "Datasheet" "https://product.samsungsem.com/mlcc/CL21A226MAYNNN.do"
			(at 0 0 90)
			(layer "F.Fab")
			(hide yes)
			(effects
				(font
					(size 1.27 1.27)
					(thickness 0.15)
				)
			)
		)
		(property "Description" "SMT Multilayer Ceramic Capacitor, 22uF, +/-20%, 25V, X5R, 0805 [2012 Metric]"
			(at 0 0 90)
			(layer "F.Fab")
			(hide yes)
			(effects
				(font
					(size 1.27 1.27)
					(thickness 0.15)
				)
			)
		)
		(property "MPN" "CL21A226MAYNNNE"
			(at 0 0 270)
			(unlocked yes)
			(layer "F.Fab")
			(hide yes)
			(effects
				(font
					(size 1 1)
					(thickness 0.15)
				)
			)
		)
		(property "Val" "22u"
			(at 0 0 270)
			(unlocked yes)
			(layer "F.Fab")
			(hide yes)
			(effects
				(font
					(size 1 1)
					(thickness 0.15)
				)
			)
		)
		(property "Voltage" "25V"
			(at 0 0 270)
			(unlocked yes)
			(layer "F.Fab")
			(hide yes)
			(effects
				(font
					(size 1 1)
					(thickness 0.15)
				)
			)
		)
		(property "Dielectric" "X5R"
			(at 0 0 270)
			(unlocked yes)
			(layer "F.Fab")
			(hide yes)
			(effects
				(font
					(size 1 1)
					(thickness 0.15)
				)
			)
		)
		(property "Manufacturer" "Samsung Electro-Mechanics"
			(at 0 0 270)
			(unlocked yes)
			(layer "F.Fab")
			(hide yes)
			(effects
				(font
					(size 1 1)
					(thickness 0.15)
				)
			)
		)
		(property "License" "Apache-2.0"
			(at 0 0 270)
			(unlocked yes)
			(layer "F.Fab")
			(hide yes)
			(effects
				(font
					(size 1 1)
					(thickness 0.15)
				)
			)
		)
		(property "Author" "Antmicro"
			(at 0 0 270)
			(unlocked yes)
			(layer "F.Fab")
			(hide yes)
			(effects
				(font
					(size 1 1)
					(thickness 0.15)
				)
			)
		)
		(property "Public" "False"
			(at 0 0 270)
			(unlocked yes)
			(layer "F.Fab")
			(hide yes)
			(effects
				(font
					(size 1 1)
					(thickness 0.15)
				)
			)
		)
		(sheetname "/Expansion connector/")
		(sheetfile "expansion_connector.kicad_sch")
		(attr smd)
		(fp_line
			(start -0.3 0.7)
			(end 0.3 0.7)
			(stroke
				(width 0.15)
				(type solid)
			)
			(layer "F.SilkS")
		)
		(fp_line
			(start -0.3 -0.7)
			(end 0.3 -0.7)
			(stroke
				(width 0.15)
				(type solid)
			)
			(layer "F.SilkS")
		)
		(fp_poly
			(pts
				(xy 1.95 -0.9) (xy -1.95 -0.9) (xy -1.95 0.9) (xy 1.95 0.9)
			)
			(stroke
				(width 0.05)
				(type default)
			)
			(fill no)
			(layer "F.CrtYd")
		)
		(fp_poly
			(pts
				(xy -0.95 -0.675001) (xy 0.95 -0.675001) (xy 0.95 0.675001) (xy -0.95 0.675001)
			)
			(stroke
				(width 0.15)
				(type solid)
			)
			(fill no)
			(layer "F.Fab")
		)
		(fp_text user "${REFERENCE}"
			(at -1.899999 3.947 90)
			(layer "F.Fab")
			(effects
				(font
					(size 0.7 0.7)
					(thickness 0.15)
				)
				(justify right top)
			)
		)
		(fp_text user "License: Apache-2.0"
			(at -1.9 4.947 90)
			(layer "F.Fab")
			(effects
				(font
					(size 0.7 0.7)
					(thickness 0.15)
				)
				(justify right top)
			)
		)
		(fp_text user "Author: Antmicro"
			(at -1.9 5.947 90)
			(layer "F.Fab")
			(effects
				(font
					(size 0.7 0.7)
					(thickness 0.15)
				)
				(justify right top)
			)
		)
		(pad "1" smd roundrect
			(at -1.099999 0 270)
			(size 1.2 1.3)
			(layers "F.Cu" "F.Mask" "F.Paste")
			(roundrect_rratio 0.25)
			(net 1 "GND")
			(pintype "passive")
		)
		(pad "2" smd roundrect
			(at 1.099999 0 270)
			(size 1.2 1.3)
			(layers "F.Cu" "F.Mask" "F.Paste")
			(roundrect_rratio 0.25)
			(net 295 "/Expansion connector/+V_{ADJ}")
			(pintype "passive")
		)
	)
	(footprint "antmicro-footprints:C_0805_2012Metric"
		(layer "F.Cu")
		(at 167.7 73.32 -90)
		(descr "Capacitor SMD 0805")
		(tags "capacitor SMD 0805")
		(property "Reference" "C297"
			(at 1.78449 -1.468678 90)
			(layer "F.SilkS")
			(effects
				(font
					(size 0.7 0.7)
					(thickness 0.15)
				)
				(justify right top)
			)
		)
		(property "Value" "C_22u_25V_0805"
			(at -2.055717 1.963152 90)
			(layer "F.Fab")
			(effects
				(font
					(size 0.7 0.7)
					(thickness 0.15)
				)
				(justify right top)
			)
		)
		(property "Datasheet" "https://product.samsungsem.com/mlcc/CL21A226MAYNNN.do"
			(at 0 0 90)
			(layer "F.Fab")
			(hide yes)
			(effects
				(font
					(size 1.27 1.27)
					(thickness 0.15)
				)
			)
		)
		(property "Description" "SMT Multilayer Ceramic Capacitor, 22uF, +/-20%, 25V, X5R, 0805 [2012 Metric]"
			(at 0 0 90)
			(layer "F.Fab")
			(hide yes)
			(effects
				(font
					(size 1.27 1.27)
					(thickness 0.15)
				)
			)
		)
		(property "MPN" "CL21A226MAYNNNE"
			(at 0 0 270)
			(unlocked yes)
			(layer "F.Fab")
			(hide yes)
			(effects
				(font
					(size 1 1)
					(thickness 0.15)
				)
			)
		)
		(property "Manufacturer" "Samsung Electro-Mechanics"
			(at 0 0 270)
			(unlocked yes)
			(layer "F.Fab")
			(hide yes)
			(effects
				(font
					(size 1 1)
					(thickness 0.15)
				)
			)
		)
		(property "License" "Apache-2.0"
			(at 0 0 270)
			(unlocked yes)
			(layer "F.Fab")
			(hide yes)
			(effects
				(font
					(size 1 1)
					(thickness 0.15)
				)
			)
		)
		(property "Author" "Antmicro"
			(at 0 0 270)
			(unlocked yes)
			(layer "F.Fab")
			(hide yes)
			(effects
				(font
					(size 1 1)
					(thickness 0.15)
				)
			)
		)
		(property "Val" "22u"
			(at 0 0 270)
			(unlocked yes)
			(layer "F.Fab")
			(hide yes)
			(effects
				(font
					(size 1 1)
					(thickness 0.15)
				)
			)
		)
		(property "Voltage" "25V"
			(at 0 0 270)
			(unlocked yes)
			(layer "F.Fab")
			(hide yes)
			(effects
				(font
					(size 1 1)
					(thickness 0.15)
				)
			)
		)
		(property "Dielectric" "X5R"
			(at 0 0 270)
			(unlocked yes)
			(layer "F.Fab")
			(hide yes)
			(effects
				(font
					(size 1 1)
					(thickness 0.15)
				)
			)
		)
		(property "Public" "False"
			(at 0 0 270)
			(unlocked yes)
			(layer "F.Fab")
			(hide yes)
			(effects
				(font
					(size 1 1)
					(thickness 0.15)
				)
			)
		)
		(component_classes
			(class "DCDC_20V")
		)
		(sheetname "/DCDC/")
		(sheetfile "dcdc.kicad_sch")
		(attr smd)
		(fp_line
			(start -0.3 0.7)
			(end 0.3 0.7)
			(stroke
				(width 0.15)
				(type solid)
			)
			(layer "F.SilkS")
		)
		(fp_line
			(start -0.3 -0.7)
			(end 0.3 -0.7)
			(stroke
				(width 0.15)
				(type solid)
			)
			(layer "F.SilkS")
		)
		(fp_rect
			(start 1.95 -0.9)
			(end -1.95 0.9)
			(stroke
				(width 0.05)
				(type default)
			)
			(fill no)
			(layer "F.CrtYd")
		)
		(fp_rect
			(start -0.95 -0.675)
			(end 0.95 0.675)
			(stroke
				(width 0.15)
				(type solid)
			)
			(fill no)
			(layer "F.Fab")
		)
		(fp_text user "Author: Antmicro"
			(at -1.9 5.947 90)
			(layer "F.Fab")
			(effects
				(font
					(size 0.7 0.7)
					(thickness 0.15)
				)
				(justify right top)
			)
		)
		(fp_text user "${REFERENCE}"
			(at -1.9 3.947 90)
			(layer "F.Fab")
			(effects
				(font
					(size 0.7 0.7)
					(thickness 0.15)
				)
				(justify right top)
			)
		)
		(fp_text user "License: Apache-2.0"
			(at -1.9 4.947 90)
			(layer "F.Fab")
			(effects
				(font
					(size 0.7 0.7)
					(thickness 0.15)
				)
				(justify right top)
			)
		)
		(pad "1" smd roundrect
			(at -1.1 0 270)
			(size 1.2 1.3)
			(layers "F.Cu" "F.Mask" "F.Paste")
			(roundrect_rratio 0.25)
			(net 1 "GND")
			(pintype "passive")
		)
		(pad "2" smd roundrect
			(at 1.1 0 270)
			(size 1.2 1.3)
			(layers "F.Cu" "F.Mask" "F.Paste")
			(roundrect_rratio 0.25)
			(net 1105 "/DCDC/20V_OUT")
			(pintype "passive")
		)
	)
	(footprint "antmicro-footprints:R_0402_1005Metric"
		(layer "F.Cu")
		(at 171.919468 117.806 90)
		(descr "Resistor SMD 0402")
		(tags "resistor SMD 0402")
		(property "Reference" "R368"
			(at -0.822484 -5.162165 90)
			(layer "F.SilkS")
			(effects
				(font
					(size 0.7 0.7)
					(thickness 0.15)
				)
				(justify left bottom)
			)
		)
		(property "Value" "R_27R_0402"
			(at -1.011843 1.772047 90)
			(layer "F.Fab")
			(effects
				(font
					(size 0.7 0.7)
					(thickness 0.15)
				)
				(justify left bottom)
			)
		)
		(property "Datasheet" "https://www.bourns.com/docs/product-datasheets/cr.pdf"
			(at 0 0 90)
			(layer "F.Fab")
			(hide yes)
			(effects
				(font
					(size 1.27 1.27)
					(thickness 0.15)
				)
			)
		)
		(property "Description" "SMD Chip Resistor, 27 ohm, ± 1%, 63 mW, 0402 [1005 Metric], Thick Film, General Purpose"
			(at 0 0 90)
			(layer "F.Fab")
			(hide yes)
			(effects
				(font
					(size 1.27 1.27)
					(thickness 0.15)
				)
			)
		)
		(property "Manufacturer" "Bourns"
			(at 0 0 90)
			(unlocked yes)
			(layer "F.Fab")
			(hide yes)
			(effects
				(font
					(size 1 1)
					(thickness 0.15)
				)
			)
		)
		(property "MPN" "CR0402-FX-27R0GLF"
			(at 0 0 90)
			(unlocked yes)
			(layer "F.Fab")
			(hide yes)
			(effects
				(font
					(size 1 1)
					(thickness 0.15)
				)
			)
		)
		(property "Val" "27R"
			(at 0 0 90)
			(unlocked yes)
			(layer "F.Fab")
			(hide yes)
			(effects
				(font
					(size 1 1)
					(thickness 0.15)
				)
			)
		)
		(property "License" "Apache-2.0"
			(at 0 0 90)
			(unlocked yes)
			(layer "F.Fab")
			(hide yes)
			(effects
				(font
					(size 1 1)
					(thickness 0.15)
				)
			)
		)
		(property "Author" "Antmicro"
			(at 0 0 90)
			(unlocked yes)
			(layer "F.Fab")
			(hide yes)
			(effects
				(font
					(size 1 1)
					(thickness 0.15)
				)
			)
		)
		(property "Tolerance" "1%"
			(at 0 0 90)
			(unlocked yes)
			(layer "F.Fab")
			(hide yes)
			(effects
				(font
					(size 1 1)
					(thickness 0.15)
				)
			)
		)
		(sheetname "/DCDC/")
		(sheetfile "dcdc.kicad_sch")
		(attr smd)
		(fp_rect
			(start -0.925 -0.47)
			(end 0.925 0.47)
			(stroke
				(width 0.05)
				(type default)
			)
			(fill no)
			(layer "F.CrtYd")
		)
		(fp_rect
			(start -0.5 -0.25)
			(end 0.5 0.25)
			(stroke
				(width 0.15)
				(type solid)
			)
			(fill no)
			(layer "F.Fab")
		)
		(fp_text user "Author: Antmicro"
			(at -0.95 4.169 90)
			(layer "F.Fab")
			(effects
				(font
					(size 0.7 0.7)
					(thickness 0.15)
				)
				(justify left bottom)
			)
		)
		(fp_text user "License: Apache-2.0"
			(at -0.95 5.169 90)
			(layer "F.Fab")
			(effects
				(font
					(size 0.7 0.7)
					(thickness 0.15)
				)
				(justify left bottom)
			)
		)
		(fp_text user "${REFERENCE}"
			(at -0.95 3.168 90)
			(layer "F.Fab")
			(effects
				(font
					(size 0.7 0.7)
					(thickness 0.15)
				)
				(justify left bottom)
			)
		)
		(pad "1" smd roundrect
			(at -0.48 0 90)
			(size 0.59 0.64)
			(layers "F.Cu" "F.Mask" "F.Paste")
			(roundrect_rratio 0.25)
			(net 1161 "Net-(U50-IN-)")
			(pintype "passive")
		)
		(pad "2" smd roundrect
			(at 0.48 0 90)
			(size 0.59 0.64)
			(layers "F.Cu" "F.Mask" "F.Paste")
			(roundrect_rratio 0.25)
			(net 5 "+5V")
			(pintype "passive")
		)
	)
	(footprint "antmicro-footprints:R_0402_1005Metric"
		(layer "F.Cu")
		(at 167 145.6 90)
		(descr "Resistor SMD 0402")
		(tags "resistor SMD 0402")
		(property "Reference" "R28"
			(at 4.3 2.5 90)
			(layer "F.SilkS")
			(effects
				(font
					(size 0.7 0.7)
					(thickness 0.15)
				)
				(justify left bottom)
			)
		)
		(property "Value" "R_0R_0402"
			(at -1.011843 1.772047 90)
			(layer "F.Fab")
			(effects
				(font
					(size 0.7 0.7)
					(thickness 0.15)
				)
				(justify left bottom)
			)
		)
		(property "Datasheet" "https://industrial.panasonic.com/cdbs/www-data/pdf/RDA0000/AOA0000C301.pdf"
			(at 0 0 90)
			(layer "F.Fab")
			(hide yes)
			(effects
				(font
					(size 1.27 1.27)
					(thickness 0.15)
				)
			)
		)
		(property "Description" "SMD Chip Resistor, Jumper, 0 ohm, 100 mW, 0402 [1005 Metric], Thick Film, General Purpose"
			(at 0 0 90)
			(layer "F.Fab")
			(hide yes)
			(effects
				(font
					(size 1.27 1.27)
					(thickness 0.15)
				)
			)
		)
		(property "MPN" "ERJ2GE0R00X"
			(at 0 0 90)
			(unlocked yes)
			(layer "F.Fab")
			(hide yes)
			(effects
				(font
					(size 1 1)
					(thickness 0.15)
				)
			)
		)
		(property "Manufacturer" "Panasonic"
			(at 0 0 90)
			(unlocked yes)
			(layer "F.Fab")
			(hide yes)
			(effects
				(font
					(size 1 1)
					(thickness 0.15)
				)
			)
		)
		(property "License" "Apache-2.0"
			(at 0 0 90)
			(unlocked yes)
			(layer "F.Fab")
			(hide yes)
			(effects
				(font
					(size 1 1)
					(thickness 0.15)
				)
			)
		)
		(property "Author" "Antmicro"
			(at 0 0 90)
			(unlocked yes)
			(layer "F.Fab")
			(hide yes)
			(effects
				(font
					(size 1 1)
					(thickness 0.15)
				)
			)
		)
		(property "Val" "0R"
			(at 0 0 90)
			(unlocked yes)
			(layer "F.Fab")
			(hide yes)
			(effects
				(font
					(size 1 1)
					(thickness 0.15)
				)
			)
		)
		(property "Tolerance" "~"
			(at 0 0 90)
			(unlocked yes)
			(layer "F.Fab")
			(hide yes)
			(effects
				(font
					(size 1 1)
					(thickness 0.15)
				)
			)
		)
		(property "Current" "1A"
			(at 0 0 270)
			(unlocked yes)
			(layer "F.Fab")
			(hide yes)
			(effects
				(font
					(size 1 1)
					(thickness 0.15)
				)
			)
		)
		(sheetname "/Peripherals/")
		(sheetfile "peripherals.kicad_sch")
		(attr smd)
		(fp_rect
			(start -0.925 -0.47)
			(end 0.925 0.47)
			(stroke
				(width 0.05)
				(type default)
			)
			(fill no)
			(layer "F.CrtYd")
		)
		(fp_rect
			(start -0.5 -0.25)
			(end 0.5 0.25)
			(stroke
				(width 0.15)
				(type solid)
			)
			(fill no)
			(layer "F.Fab")
		)
		(fp_text user "License: Apache-2.0"
			(at -0.95 5.169 90)
			(layer "F.Fab")
			(effects
				(font
					(size 0.7 0.7)
					(thickness 0.15)
				)
				(justify left bottom)
			)
		)
		(fp_text user "Author: Antmicro"
			(at -0.95 4.169 90)
			(layer "F.Fab")
			(effects
				(font
					(size 0.7 0.7)
					(thickness 0.15)
				)
				(justify left bottom)
			)
		)
		(fp_text user "${REFERENCE}"
			(at -0.95 3.168 90)
			(layer "F.Fab")
			(effects
				(font
					(size 0.7 0.7)
					(thickness 0.15)
				)
				(justify left bottom)
			)
		)
		(pad "1" smd roundrect
			(at -0.48 0 90)
			(size 0.59 0.64)
			(layers "F.Cu" "F.Mask" "F.Paste")
			(roundrect_rratio 0.25)
			(net 5 "+5V")
			(pintype "passive")
		)
		(pad "2" smd roundrect
			(at 0.48 0 90)
			(size 0.59 0.64)
			(layers "F.Cu" "F.Mask" "F.Paste")
			(roundrect_rratio 0.25)
			(net 1043 "/Peripherals/FAN_VDD")
			(pintype "passive")
		)
	)
)
